(kicad_pcb
	(version 20241229)
	(generator "pcbnew")
	(generator_version "9.0")
	(general
		(thickness 1.599998)
		(legacy_teardrops no)
	)
	(paper "A4")
	(title_block
		(title "Artix - Datacenter Secure Control Module (DC-SCM)")
		(date "2024-11-06")
		(rev "1.1.3")
		(comment 9 "footprints 141-144 of 544")
	)
	(layers
		(0 "F.Cu" signal)
		(4 "In1.Cu" signal)
		(6 "In2.Cu" signal)
		(8 "In3.Cu" signal)
		(10 "In4.Cu" signal)
		(12 "In5.Cu" signal)
		(14 "In6.Cu" signal)
		(2 "B.Cu" signal)
		(9 "F.Adhes" user "F.Adhesive")
		(11 "B.Adhes" user "B.Adhesive")
		(13 "F.Paste" user)
		(15 "B.Paste" user)
		(5 "F.SilkS" user "F.Silkscreen")
		(7 "B.SilkS" user "B.Silkscreen")
		(1 "F.Mask" user)
		(3 "B.Mask" user)
		(17 "Dwgs.User" user "User.Drawings")
		(19 "Cmts.User" user "User.Comments")
		(21 "Eco1.User" user "User.Eco1")
		(23 "Eco2.User" user "User.Eco2")
		(25 "Edge.Cuts" user)
		(27 "Margin" user)
		(31 "F.CrtYd" user "F.Courtyard")
		(29 "B.CrtYd" user "B.Courtyard")
		(35 "F.Fab" user)
		(33 "B.Fab" user)
	)
	(footprint "antmicro-footprints:QFN-8_2x1.5mm"
		(layer "F.Cu")
		(at 86.995 104.125 180)
		(property "Reference" "U10"
			(at 0.885 -2.245 180)
			(layer "F.SilkS")
			(effects
				(font
					(size 0.7 0.7)
					(thickness 0.15)
				)
				(justify left bottom)
			)
		)
		(property "Value" "TPS62823DLCT"
			(at 0 2.2 180)
			(layer "F.Fab")
			(effects
				(font
					(size 0.7 0.7)
					(thickness 0.15)
				)
				(justify left bottom)
			)
		)
		(property "Datasheet" "https://www.ti.com/lit/ds/symlink/tps62823.pdf?ts=1685970309606&ref_url=https%253A%252F%252Fwww.ti.com%252Fproduct%252FTPS62823%252Fpart-details%252FTPS62823DLCT"
			(at 0 0 180)
			(layer "F.Fab")
			(hide yes)
			(effects
				(font
					(size 1.27 1.27)
					(thickness 0.15)
				)
			)
		)
		(property "Description" "DC/DC converter"
			(at 0 0 180)
			(layer "F.Fab")
			(hide yes)
			(effects
				(font
					(size 1.27 1.27)
					(thickness 0.15)
				)
			)
		)
		(property "Author" "Antmicro"
			(at 173.99 208.25 0)
			(layer "F.Fab")
			(hide yes)
			(effects
				(font
					(size 1 1)
					(thickness 0.15)
				)
			)
		)
		(property "License" "Apache-2.0"
			(at 173.99 208.25 0)
			(layer "F.Fab")
			(hide yes)
			(effects
				(font
					(size 1 1)
					(thickness 0.15)
				)
			)
		)
		(property "MPN" "TPS62823DLCT"
			(at 173.99 208.25 0)
			(layer "F.Fab")
			(hide yes)
			(effects
				(font
					(size 1 1)
					(thickness 0.15)
				)
			)
		)
		(property "Manufacturer" "Texas Instruments"
			(at 173.99 208.25 0)
			(layer "F.Fab")
			(hide yes)
			(effects
				(font
					(size 1 1)
					(thickness 0.15)
				)
			)
		)
		(sheetname "/Power supply/")
		(sheetfile "power-supply.kicad_sch")
		(attr smd)
		(fp_line
			(start -0.25 -1.05)
			(end 0.9 -1.05)
			(stroke
				(width 0.15)
				(type solid)
			)
			(layer "F.SilkS")
		)
		(fp_line
			(start -0.9 1.05)
			(end 0.9 1.05)
			(stroke
				(width 0.15)
				(type solid)
			)
			(layer "F.SilkS")
		)
		(fp_circle
			(center -0.9 -1.05)
			(end -0.849 -1.05)
			(stroke
				(width 0.15)
				(type solid)
			)
			(fill yes)
			(layer "F.SilkS")
		)
		(fp_rect
			(start -1.1 -1.25)
			(end 1.1 1.25)
			(stroke
				(width 0.05)
				(type solid)
			)
			(fill no)
			(layer "F.CrtYd")
		)
		(fp_line
			(start 0.998 0.998)
			(end -1 0.998)
			(stroke
				(width 0.15)
				(type solid)
			)
			(layer "F.Fab")
		)
		(fp_line
			(start 0.998 -1)
			(end 0.998 0.998)
			(stroke
				(width 0.15)
				(type solid)
			)
			(layer "F.Fab")
		)
		(fp_line
			(start -0.5 -1)
			(end 0.998 -1)
			(stroke
				(width 0.15)
				(type solid)
			)
			(layer "F.Fab")
		)
		(fp_line
			(start -1 0.998)
			(end -1 -0.5)
			(stroke
				(width 0.15)
				(type solid)
			)
			(layer "F.Fab")
		)
		(fp_line
			(start -1 -0.5)
			(end -0.5 -1)
			(stroke
				(width 0.15)
				(type solid)
			)
			(layer "F.Fab")
		)
		(pad "1" smd rect
			(at -0.677 -0.75 180)
			(size 0.55 0.25)
			(layers "F.Cu" "F.Mask" "F.Paste")
			(net 314 "Net-(U10-EN)")
			(pinfunction "EN")
			(pintype "input")
		)
		(pad "2" smd rect
			(at -0.677 -0.25 180)
			(size 0.55 0.25)
			(layers "F.Cu" "F.Mask" "F.Paste")
			(net 113 "Net-(U10-FB)")
			(pinfunction "FB")
			(pintype "bidirectional")
		)
		(pad "3" smd rect
			(at -0.677 0.248 180)
			(size 0.55 0.25)
			(layers "F.Cu" "F.Mask" "F.Paste")
			(net 1 "GND")
			(pinfunction "AGND")
			(pintype "power_in")
		)
		(pad "4" smd rect
			(at -0.677 0.748 180)
			(size 0.55 0.25)
			(layers "F.Cu" "F.Mask" "F.Paste")
			(net 528 "unconnected-(U10-NC-Pad4)")
			(pinfunction "NC")
			(pintype "no_connect")
		)
		(pad "5" smd rect
			(at 0.675 0.748 180)
			(size 0.55 0.25)
			(layers "F.Cu" "F.Mask" "F.Paste")
			(net 1 "GND")
			(pinfunction "PGND")
			(pintype "power_in")
		)
		(pad "6" smd rect
			(at 0.675 0.248 180)
			(size 0.55 0.25)
			(layers "F.Cu" "F.Mask" "F.Paste")
			(net 285 "Net-(U10-SW)")
			(pinfunction "SW")
			(pintype "bidirectional")
		)
		(pad "7" smd rect
			(at 0.675 -0.25 180)
			(size 0.55 0.25)
			(layers "F.Cu" "F.Mask" "F.Paste")
			(net 4 "VCC5V0")
			(pinfunction "VIN")
			(pintype "power_in")
		)
		(pad "8" smd rect
			(at 0.675 -0.75 180)
			(size 0.55 0.25)
			(layers "F.Cu" "F.Mask" "F.Paste")
			(net 529 "unconnected-(U10-PG-Pad8)")
			(pinfunction "PG")
			(pintype "output+no_connect")
		)
	)
	(footprint "antmicro-footprints:L_Vishay-IHLP-1212AE"
		(layer "F.Cu")
		(at 82.55 79.825 90)
		(property "Reference" "L4"
			(at -2.735 -2.02 180)
			(layer "F.SilkS")
			(effects
				(font
					(size 0.7 0.7)
					(thickness 0.15)
				)
				(justify left bottom)
			)
		)
		(property "Value" "L_470n_6.7A_Vishay-IHLP-1212AE-11"
			(at 1.278 3.401 90)
			(layer "F.Fab")
			(effects
				(font
					(size 0.7 0.7)
					(thickness 0.15)
				)
				(justify left bottom)
			)
		)
		(property "Datasheet" "https://www.vishay.com/docs/34300/ihlp-1212ae-11.pdf"
			(at 0 0 90)
			(layer "F.Fab")
			(hide yes)
			(effects
				(font
					(size 1.27 1.27)
					(thickness 0.15)
				)
			)
		)
		(property "Description" "Power Inductor (SMT), 470 nH, 6.7 A, Shielded, 6.7 A"
			(at 0 0 90)
			(layer "F.Fab")
			(hide yes)
			(effects
				(font
					(size 1.27 1.27)
					(thickness 0.15)
				)
			)
		)
		(property "Author" "Antmicro"
			(at 162.375 -2.725 0)
			(layer "F.Fab")
			(hide yes)
			(effects
				(font
					(size 1 1)
					(thickness 0.15)
				)
			)
		)
		(property "IMax" "6.7 A"
			(at 162.375 -2.725 0)
			(layer "F.Fab")
			(hide yes)
			(effects
				(font
					(size 1 1)
					(thickness 0.15)
				)
			)
		)
		(property "ISat" "6.7 A"
			(at 162.375 -2.725 0)
			(layer "F.Fab")
			(hide yes)
			(effects
				(font
					(size 1 1)
					(thickness 0.15)
				)
			)
		)
		(property "License" "Apache-2.0"
			(at 162.375 -2.725 0)
			(layer "F.Fab")
			(hide yes)
			(effects
				(font
					(size 1 1)
					(thickness 0.15)
				)
			)
		)
		(property "MPN" "IHLP1212AEERR47M11"
			(at 162.375 -2.725 0)
			(layer "F.Fab")
			(hide yes)
			(effects
				(font
					(size 1 1)
					(thickness 0.15)
				)
			)
		)
		(property "Manufacturer" "Vishay"
			(at 162.375 -2.725 0)
			(layer "F.Fab")
			(hide yes)
			(effects
				(font
					(size 1 1)
					(thickness 0.15)
				)
			)
		)
		(property "Size" "3.0x3.0"
			(at 162.375 -2.725 0)
			(layer "F.Fab")
			(hide yes)
			(effects
				(font
					(size 1 1)
					(thickness 0.15)
				)
			)
		)
		(property "Val" "470n/6.7A"
			(at 162.375 -2.725 0)
			(layer "F.Fab")
			(hide yes)
			(effects
				(font
					(size 1 1)
					(thickness 0.15)
				)
			)
		)
		(sheetname "/Power supply/")
		(sheetfile "power-supply.kicad_sch")
		(attr smd)
		(fp_line
			(start 1.653 -1.6)
			(end 1.653 -0.9)
			(stroke
				(width 0.15)
				(type solid)
			)
			(layer "F.SilkS")
		)
		(fp_line
			(start -1.647 -1.6)
			(end 1.653 -1.6)
			(stroke
				(width 0.15)
				(type solid)
			)
			(layer "F.SilkS")
		)
		(fp_line
			(start -1.647 -0.9)
			(end -1.647 -1.6)
			(stroke
				(width 0.15)
				(type solid)
			)
			(layer "F.SilkS")
		)
		(fp_line
			(start 1.653 0.9)
			(end 1.653 1.601)
			(stroke
				(width 0.15)
				(type solid)
			)
			(layer "F.SilkS")
		)
		(fp_line
			(start -1.647 1.6)
			(end -1.647 0.9)
			(stroke
				(width 0.15)
				(type solid)
			)
			(layer "F.SilkS")
		)
		(fp_line
			(start 1.653 1.601)
			(end -1.647 1.6)
			(stroke
				(width 0.15)
				(type solid)
			)
			(layer "F.SilkS")
		)
		(fp_rect
			(start -2.35 -1.85)
			(end 2.35 1.85)
			(stroke
				(width 0.05)
				(type solid)
			)
			(fill no)
			(layer "F.CrtYd")
		)
		(fp_rect
			(start -1.803 -1.601)
			(end 1.803 1.601)
			(stroke
				(width 0.15)
				(type solid)
			)
			(fill no)
			(layer "F.Fab")
		)
		(pad "1" smd roundrect
			(at -1.35 0 90)
			(size 1.5 1.2)
			(layers "F.Cu" "F.Mask" "F.Paste")
			(roundrect_rratio 0.1)
			(net 289 "Net-(U12-SW)")
			(pintype "passive")
		)
		(pad "2" smd roundrect
			(at 1.35 0 90)
			(size 1.5 1.2)
			(layers "F.Cu" "F.Mask" "F.Paste")
			(roundrect_rratio 0.1)
			(net 276 "Net-(C81-Pad2)")
			(pintype "passive")
		)
	)
	(footprint "antmicro-footprints:L_Vishay-IHLP-1212AE"
		(layer "F.Cu")
		(at 82.65 101.8 90)
		(property "Reference" "L2"
			(at -2.067 -0.6545 90)
			(layer "F.SilkS")
			(effects
				(font
					(size 0.7 0.7)
					(thickness 0.15)
				)
				(justify left bottom)
			)
		)
		(property "Value" "L_470n_6.7A_Vishay-IHLP-1212AE-11"
			(at 1.278 3.401 90)
			(layer "F.Fab")
			(effects
				(font
					(size 0.7 0.7)
					(thickness 0.15)
				)
				(justify left bottom)
			)
		)
		(property "Datasheet" "https://www.vishay.com/docs/34300/ihlp-1212ae-11.pdf"
			(at 0 0 90)
			(layer "F.Fab")
			(hide yes)
			(effects
				(font
					(size 1.27 1.27)
					(thickness 0.15)
				)
			)
		)
		(property "Description" "Power Inductor (SMT), 470 nH, 6.7 A, Shielded, 6.7 A"
			(at 0 0 90)
			(layer "F.Fab")
			(hide yes)
			(effects
				(font
					(size 1.27 1.27)
					(thickness 0.15)
				)
			)
		)
		(property "Author" "Antmicro"
			(at 184.45 19.15 0)
			(layer "F.Fab")
			(hide yes)
			(effects
				(font
					(size 1 1)
					(thickness 0.15)
				)
			)
		)
		(property "IMax" "6.7 A"
			(at 184.45 19.15 0)
			(layer "F.Fab")
			(hide yes)
			(effects
				(font
					(size 1 1)
					(thickness 0.15)
				)
			)
		)
		(property "ISat" "6.7 A"
			(at 184.45 19.15 0)
			(layer "F.Fab")
			(hide yes)
			(effects
				(font
					(size 1 1)
					(thickness 0.15)
				)
			)
		)
		(property "License" "Apache-2.0"
			(at 184.45 19.15 0)
			(layer "F.Fab")
			(hide yes)
			(effects
				(font
					(size 1 1)
					(thickness 0.15)
				)
			)
		)
		(property "MPN" "IHLP1212AEERR47M11"
			(at 184.45 19.15 0)
			(layer "F.Fab")
			(hide yes)
			(effects
				(font
					(size 1 1)
					(thickness 0.15)
				)
			)
		)
		(property "Manufacturer" "Vishay"
			(at 184.45 19.15 0)
			(layer "F.Fab")
			(hide yes)
			(effects
				(font
					(size 1 1)
					(thickness 0.15)
				)
			)
		)
		(property "Size" "3.0x3.0"
			(at 184.45 19.15 0)
			(layer "F.Fab")
			(hide yes)
			(effects
				(font
					(size 1 1)
					(thickness 0.15)
				)
			)
		)
		(property "Val" "470n/6.7A"
			(at 184.45 19.15 0)
			(layer "F.Fab")
			(hide yes)
			(effects
				(font
					(size 1 1)
					(thickness 0.15)
				)
			)
		)
		(sheetname "/Power supply/")
		(sheetfile "power-supply.kicad_sch")
		(attr smd)
		(fp_line
			(start 1.653 -1.6)
			(end 1.653 -0.9)
			(stroke
				(width 0.15)
				(type solid)
			)
			(layer "F.SilkS")
		)
		(fp_line
			(start -1.647 -1.6)
			(end 1.653 -1.6)
			(stroke
				(width 0.15)
				(type solid)
			)
			(layer "F.SilkS")
		)
		(fp_line
			(start -1.647 -0.9)
			(end -1.647 -1.6)
			(stroke
				(width 0.15)
				(type solid)
			)
			(layer "F.SilkS")
		)
		(fp_line
			(start 1.653 0.9)
			(end 1.653 1.601)
			(stroke
				(width 0.15)
				(type solid)
			)
			(layer "F.SilkS")
		)
		(fp_line
			(start -1.647 1.6)
			(end -1.647 0.9)
			(stroke
				(width 0.15)
				(type solid)
			)
			(layer "F.SilkS")
		)
		(fp_line
			(start 1.653 1.601)
			(end -1.647 1.6)
			(stroke
				(width 0.15)
				(type solid)
			)
			(layer "F.SilkS")
		)
		(fp_rect
			(start -2.35 -1.85)
			(end 2.35 1.85)
			(stroke
				(width 0.05)
				(type solid)
			)
			(fill no)
			(layer "F.CrtYd")
		)
		(fp_rect
			(start -1.803 -1.601)
			(end 1.803 1.601)
			(stroke
				(width 0.15)
				(type solid)
			)
			(fill no)
			(layer "F.Fab")
		)
		(pad "1" smd roundrect
			(at -1.35 0 90)
			(size 1.5 1.2)
			(layers "F.Cu" "F.Mask" "F.Paste")
			(roundrect_rratio 0.1)
			(net 285 "Net-(U10-SW)")
			(pintype "passive")
		)
		(pad "2" smd roundrect
			(at 1.35 0 90)
			(size 1.5 1.2)
			(layers "F.Cu" "F.Mask" "F.Paste")
			(roundrect_rratio 0.1)
			(net 274 "Net-(C79-Pad2)")
			(pintype "passive")
		)
	)
	(footprint "antmicro-footprints:L_Vishay-IHLP-1212AE"
		(layer "F.Cu")
		(at 82.5545 94.6 90)
		(property "Reference" "L3"
			(at -2.067 -0.6545 90)
			(layer "F.SilkS")
			(effects
				(font
					(size 0.7 0.7)
					(thickness 0.15)
				)
				(justify left bottom)
			)
		)
		(property "Value" "L_470n_6.7A_Vishay-IHLP-1212AE-11"
			(at 1.278 3.401 90)
			(layer "F.Fab")
			(effects
				(font
					(size 0.7 0.7)
					(thickness 0.15)
				)
				(justify left bottom)
			)
		)
		(property "Datasheet" "https://www.vishay.com/docs/34300/ihlp-1212ae-11.pdf"
			(at 0 0 90)
			(layer "F.Fab")
			(hide yes)
			(effects
				(font
					(size 1.27 1.27)
					(thickness 0.15)
				)
			)
		)
		(property "Description" "Power Inductor (SMT), 470 nH, 6.7 A, Shielded, 6.7 A"
			(at 0 0 90)
			(layer "F.Fab")
			(hide yes)
			(effects
				(font
					(size 1.27 1.27)
					(thickness 0.15)
				)
			)
		)
		(property "Author" "Antmicro"
			(at 177.1545 12.0455 0)
			(layer "F.Fab")
			(hide yes)
			(effects
				(font
					(size 1 1)
					(thickness 0.15)
				)
			)
		)
		(property "IMax" "6.7 A"
			(at 177.1545 12.0455 0)
			(layer "F.Fab")
			(hide yes)
			(effects
				(font
					(size 1 1)
					(thickness 0.15)
				)
			)
		)
		(property "ISat" "6.7 A"
			(at 177.1545 12.0455 0)
			(layer "F.Fab")
			(hide yes)
			(effects
				(font
					(size 1 1)
					(thickness 0.15)
				)
			)
		)
		(property "License" "Apache-2.0"
			(at 177.1545 12.0455 0)
			(layer "F.Fab")
			(hide yes)
			(effects
				(font
					(size 1 1)
					(thickness 0.15)
				)
			)
		)
		(property "MPN" "IHLP1212AEERR47M11"
			(at 177.1545 12.0455 0)
			(layer "F.Fab")
			(hide yes)
			(effects
				(font
					(size 1 1)
					(thickness 0.15)
				)
			)
		)
		(property "Manufacturer" "Vishay"
			(at 177.1545 12.0455 0)
			(layer "F.Fab")
			(hide yes)
			(effects
				(font
					(size 1 1)
					(thickness 0.15)
				)
			)
		)
		(property "Size" "3.0x3.0"
			(at 177.1545 12.0455 0)
			(layer "F.Fab")
			(hide yes)
			(effects
				(font
					(size 1 1)
					(thickness 0.15)
				)
			)
		)
		(property "Val" "470n/6.7A"
			(at 177.1545 12.0455 0)
			(layer "F.Fab")
			(hide yes)
			(effects
				(font
					(size 1 1)
					(thickness 0.15)
				)
			)
		)
		(sheetname "/Power supply/")
		(sheetfile "power-supply.kicad_sch")
		(attr smd)
		(fp_line
			(start 1.653 -1.6)
			(end 1.653 -0.9)
			(stroke
				(width 0.15)
				(type solid)
			)
			(layer "F.SilkS")
		)
		(fp_line
			(start -1.647 -1.6)
			(end 1.653 -1.6)
			(stroke
				(width 0.15)
				(type solid)
			)
			(layer "F.SilkS")
		)
		(fp_line
			(start -1.647 -0.9)
			(end -1.647 -1.6)
			(stroke
				(width 0.15)
				(type solid)
			)
			(layer "F.SilkS")
		)
		(fp_line
			(start 1.653 0.9)
			(end 1.653 1.601)
			(stroke
				(width 0.15)
				(type solid)
			)
			(layer "F.SilkS")
		)
		(fp_line
			(start -1.647 1.6)
			(end -1.647 0.9)
			(stroke
				(width 0.15)
				(type solid)
			)
			(layer "F.SilkS")
		)
		(fp_line
			(start 1.653 1.601)
			(end -1.647 1.6)
			(stroke
				(width 0.15)
				(type solid)
			)
			(layer "F.SilkS")
		)
		(fp_rect
			(start -2.35 -1.85)
			(end 2.35 1.85)
			(stroke
				(width 0.05)
				(type solid)
			)
			(fill no)
			(layer "F.CrtYd")
		)
		(fp_rect
			(start -1.803 -1.601)
			(end 1.803 1.601)
			(stroke
				(width 0.15)
				(type solid)
			)
			(fill no)
			(layer "F.Fab")
		)
		(pad "1" smd roundrect
			(at -1.35 0 90)
			(size 1.5 1.2)
			(layers "F.Cu" "F.Mask" "F.Paste")
			(roundrect_rratio 0.1)
			(net 288 "Net-(U11-SW)")
			(pintype "passive")
		)
		(pad "2" smd roundrect
			(at 1.35 0 90)
			(size 1.5 1.2)
			(layers "F.Cu" "F.Mask" "F.Paste")
			(roundrect_rratio 0.1)
			(net 275 "Net-(C80-Pad2)")
			(pintype "passive")
		)
	)
)
